(kicad_pcb
	(version 20260206)
	(generator "pcbnew")
	(generator_version "10.0")
	(general
		(thickness 1.6)
		(legacy_teardrops no)
	)
	(paper "A4")
	(title_block
		(title "Bryce Canyon_R.DPB_16317-1_OCP.brd")
		(comment 1 "Bryce Canyon / footprints 1694-1699 of 2099")
	)
	(layers
		(0 "F.Cu" signal "TOP")
		(4 "In1.Cu" signal "L2GND")
		(6 "In2.Cu" signal "L3")
		(8 "In3.Cu" signal "L4VCC")
		(10 "In4.Cu" signal "L5VCC")
		(12 "In5.Cu" signal "L6")
		(14 "In6.Cu" signal "L7GND")
		(2 "B.Cu" signal "BOTTOM")
		(9 "F.Adhes" user "F.Adhesive")
		(11 "B.Adhes" user "B.Adhesive")
		(13 "F.Paste" user "Package Geometry/Pastemask Top")
		(15 "B.Paste" user "Package Geometry/Pastemask Bottom")
		(5 "F.SilkS" user "Ref Des/Silkscreen Top")
		(7 "B.SilkS" user "Ref Des/Silkscreen Bottom")
		(1 "F.Mask" user "Board Geometry/Soldermask Top")
		(3 "B.Mask" user "Board Geometry/Soldermask Bottom")
		(17 "Dwgs.User" user "User.Drawings")
		(19 "Cmts.User" user "User.Comments")
		(21 "Eco1.User" user "User.Eco1")
		(23 "Eco2.User" user "User.Eco2")
		(25 "Edge.Cuts" user "Board Geometry/Outline")
		(27 "Margin" user)
		(31 "F.CrtYd" user "Package Geometry/Place Bound Top")
		(29 "B.CrtYd" user "Package Geometry/Place Bound Bottom")
		(35 "F.Fab" user "Ref Des/Assembly Top")
		(33 "B.Fab" user "Ref Des/Assembly Bottom")
	)
	(footprint ""
		(layer "F.Cu")
		(at 429.514 -23.876 -90)
		(property "Reference" "Q171"
			(at 0 0 270)
			(layer "F.SilkS")
			(hide yes)
			(effects
				(font
					(size 1.27 1.27)
				)
			)
		)
		(property "Value" "AO4406AL-GP"
			(at -3.707384 -1.5367 270)
			(unlocked yes)
			(layer "F.Fab")
			(hide yes)
			(effects
				(font
					(size 1.016 1.016)
					(thickness 0.1524)
				)
			)
		)
		(property "Device Type" "SOIC8H69"
			(at -3.707384 -3.0607 270)
			(unlocked yes)
			(layer "F.Fab")
			(hide yes)
			(effects
				(font
					(size 1.016 1.016)
					(thickness 0.1524)
				)
			)
		)
		(duplicate_pad_numbers_are_jumpers no)
		(fp_line
			(start -2.6289 3.4417)
			(end -2.6289 1.4732)
			(stroke
				(width 0.381)
				(type default)
			)
			(layer "F.SilkS")
		)
		(fp_line
			(start -2.7432 1.4224)
			(end -2.6416 1.4224)
			(stroke
				(width 0.1524)
				(type default)
			)
			(layer "F.SilkS")
		)
		(fp_line
			(start -2.7432 1.4224)
			(end 2.1336 1.4224)
			(stroke
				(width 0.1524)
				(type default)
			)
			(layer "F.SilkS")
		)
		(fp_line
			(start 2.1336 1.4224)
			(end 2.1336 -1.4224)
			(stroke
				(width 0.1524)
				(type default)
			)
			(layer "F.SilkS")
		)
		(fp_line
			(start -2.1844 -0.0508)
			(end -2.7178 0.508)
			(stroke
				(width 0.1524)
				(type default)
			)
			(layer "F.SilkS")
		)
		(fp_line
			(start -2.7178 -0.508)
			(end -2.1844 -0.0508)
			(stroke
				(width 0.1524)
				(type default)
			)
			(layer "F.SilkS")
		)
		(fp_line
			(start -2.7432 -1.4224)
			(end -2.7432 1.4224)
			(stroke
				(width 0.1524)
				(type default)
			)
			(layer "F.SilkS")
		)
		(fp_line
			(start 2.1336 -1.4224)
			(end -2.7432 -1.4224)
			(stroke
				(width 0.1524)
				(type default)
			)
			(layer "F.SilkS")
		)
		(fp_poly
			(pts
				(xy -2.2098 -1.4224) (xy -2.2098 1.4224) (xy 2.2098 1.4224) (xy 2.2098 -1.4224)
			)
			(stroke
				(width 0)
				(type default)
			)
			(fill yes)
			(layer "F.SilkS")
		)
		(fp_rect
			(start -2.450084 2.999994)
			(end 2.450084 -2.999994)
			(stroke
				(width 0)
				(type default)
			)
			(fill no)
			(layer "F.CrtYd")
		)
		(fp_poly
			(pts
				(xy -2.8194 3.6322) (xy -2.8194 -3.6322) (xy 2.8194 -3.6322) (xy 2.8194 1.18364) (xy 2.450084 1.18364)
				(xy 2.450084 -2.999994) (xy -2.450084 -2.999994) (xy -2.450084 2.999994) (xy 2.450084 2.999994)
				(xy 2.450084 1.18618) (xy 2.8194 1.18618) (xy 2.8194 3.6322)
			)
			(stroke
				(width 0)
				(type default)
			)
			(fill no)
			(layer "F.CrtYd")
		)
		(fp_rect
			(start -2.8194 3.6322)
			(end 2.8194 -3.6322)
			(stroke
				(width 0)
				(type default)
			)
			(fill no)
			(layer "F.Fab")
		)
		(pad "1" smd rect
			(at -1.905 2.54 270)
			(size 0.635 1.651)
			(layers "F.Cu" "F.Mask" "F.Paste")
			(net "P5V_HDD33")
		)
		(pad "2" smd rect
			(at -0.635 2.54 270)
			(size 0.635 1.651)
			(layers "F.Cu" "F.Mask" "F.Paste")
			(net "P5V_HDD33")
		)
		(pad "3" smd rect
			(at 0.635 2.54 270)
			(size 0.635 1.651)
			(layers "F.Cu" "F.Mask" "F.Paste")
			(net "P5V_HDD33")
		)
		(pad "4" smd rect
			(at 1.905 2.54 270)
			(size 0.635 1.651)
			(layers "F.Cu" "F.Mask" "F.Paste")
			(net "SW_HDD_P33")
		)
		(pad "5" smd rect
			(at 1.905 -2.54 270)
			(size 0.635 1.651)
			(layers "F.Cu" "F.Mask" "F.Paste")
			(net "P5V_B_4")
		)
		(pad "6" smd rect
			(at 0.635 -2.54 270)
			(size 0.635 1.651)
			(layers "F.Cu" "F.Mask" "F.Paste")
			(net "P5V_B_4")
		)
		(pad "7" smd rect
			(at -0.635 -2.54 270)
			(size 0.635 1.651)
			(layers "F.Cu" "F.Mask" "F.Paste")
			(net "P5V_B_4")
		)
		(pad "8" smd rect
			(at -1.905 -2.54 270)
			(size 0.635 1.651)
			(layers "F.Cu" "F.Mask" "F.Paste")
			(net "P5V_B_4")
		)
	)
	(footprint ""
		(layer "F.Cu")
		(at 176.022 -361.696)
		(property "Reference" "C548"
			(at 0 0 0)
			(layer "F.SilkS")
			(hide yes)
			(effects
				(font
					(size 1.27 1.27)
				)
			)
		)
		(property "Value" "SCD1U25V2KX-2-GP"
			(at 1.1811 -2.7051 0)
			(unlocked yes)
			(layer "F.Fab")
			(hide yes)
			(effects
				(font
					(size 1.016 1.016)
					(thickness 0.1524)
				)
			)
		)
		(property "Device Type" "C402H22"
			(at 1.1811 -4.2291 0)
			(unlocked yes)
			(layer "F.Fab")
			(hide yes)
			(effects
				(font
					(size 1.016 1.016)
					(thickness 0.1524)
				)
			)
		)
		(duplicate_pad_numbers_are_jumpers no)
		(fp_rect
			(start -0.4318 0.9525)
			(end 0.4318 -0.9525)
			(stroke
				(width 0)
				(type default)
			)
			(fill no)
			(layer "F.CrtYd")
		)
		(fp_rect
			(start -0.4318 0.9525)
			(end 0.4318 -0.9525)
			(stroke
				(width 0)
				(type default)
			)
			(fill no)
			(layer "F.Fab")
		)
		(pad "1" smd custom
			(at 0 -0.4445)
			(size 0.1524 0.1524)
			(layers "F.Cu" "F.Mask" "F.Paste")
			(net "MB0_ISTART_R")
			(options
				(clearance outline)
				(anchor circle)
			)
			(primitives
				(gr_poly
					(pts
						(arc
							(start 0.3048 -0.2032)
							(mid 0.275042 -0.275042)
							(end 0.2032 -0.3048)
						)
						(arc
							(start -0.2032 -0.3048)
							(mid -0.275042 -0.275042)
							(end -0.3048 -0.2032)
						)
						(arc
							(start -0.3048 0.2032)
							(mid -0.275042 0.275042)
							(end -0.2032 0.3048)
						)
						(arc
							(start 0.2032 0.3048)
							(mid 0.275042 0.275042)
							(end 0.3048 0.2032)
						)
					)
					(width 0)
					(fill yes)
				)
			)
		)
		(pad "2" smd custom
			(at 0 0.4445)
			(size 0.1524 0.1524)
			(layers "F.Cu" "F.Mask" "F.Paste")
			(net "AGND_CURRENT_MON")
			(options
				(clearance outline)
				(anchor circle)
			)
			(primitives
				(gr_poly
					(pts
						(arc
							(start 0.3048 -0.2032)
							(mid 0.275042 -0.275042)
							(end 0.2032 -0.3048)
						)
						(arc
							(start -0.2032 -0.3048)
							(mid -0.275042 -0.275042)
							(end -0.3048 -0.2032)
						)
						(arc
							(start -0.3048 0.2032)
							(mid -0.275042 0.275042)
							(end -0.2032 0.3048)
						)
						(arc
							(start 0.2032 0.3048)
							(mid 0.275042 0.275042)
							(end 0.3048 0.2032)
						)
					)
					(width 0)
					(fill yes)
				)
			)
		)
	)
	(footprint ""
		(layer "F.Cu")
		(at 249.33148 -217.1827 180)
		(property "Reference" "U13"
			(at 0 0 180)
			(layer "F.SilkS")
			(hide yes)
			(effects
				(font
					(size 1.27 1.27)
				)
			)
		)
		(property "Value" "24LC64-I-SN-GP"
			(at -3.707384 -1.5367 180)
			(unlocked yes)
			(layer "F.Fab")
			(hide yes)
			(effects
				(font
					(size 1.016 1.016)
					(thickness 0.1524)
				)
			)
		)
		(property "Device Type" "SOIC8H69"
			(at -3.707384 -3.0607 180)
			(unlocked yes)
			(layer "F.Fab")
			(hide yes)
			(effects
				(font
					(size 1.016 1.016)
					(thickness 0.1524)
				)
			)
		)
		(duplicate_pad_numbers_are_jumpers no)
		(fp_line
			(start 2.1336 1.4224)
			(end 2.1336 -1.4224)
			(stroke
				(width 0.1524)
				(type default)
			)
			(layer "F.SilkS")
		)
		(fp_line
			(start 2.1336 -1.4224)
			(end -2.7432 -1.4224)
			(stroke
				(width 0.1524)
				(type default)
			)
			(layer "F.SilkS")
		)
		(fp_line
			(start -2.1844 -0.0508)
			(end -2.7178 0.508)
			(stroke
				(width 0.1524)
				(type default)
			)
			(layer "F.SilkS")
		)
		(fp_line
			(start -2.6289 3.4417)
			(end -2.6289 1.4732)
			(stroke
				(width 0.381)
				(type default)
			)
			(layer "F.SilkS")
		)
		(fp_line
			(start -2.7178 -0.508)
			(end -2.1844 -0.0508)
			(stroke
				(width 0.1524)
				(type default)
			)
			(layer "F.SilkS")
		)
		(fp_line
			(start -2.7432 1.4224)
			(end 2.1336 1.4224)
			(stroke
				(width 0.1524)
				(type default)
			)
			(layer "F.SilkS")
		)
		(fp_line
			(start -2.7432 1.4224)
			(end -2.6416 1.4224)
			(stroke
				(width 0.1524)
				(type default)
			)
			(layer "F.SilkS")
		)
		(fp_line
			(start -2.7432 -1.4224)
			(end -2.7432 1.4224)
			(stroke
				(width 0.1524)
				(type default)
			)
			(layer "F.SilkS")
		)
		(fp_poly
			(pts
				(xy -2.2098 -1.4224) (xy -2.2098 1.4224) (xy 2.2098 1.4224) (xy 2.2098 -1.4224)
			)
			(stroke
				(width 0)
				(type default)
			)
			(fill yes)
			(layer "F.SilkS")
		)
		(fp_rect
			(start -2.450084 2.999994)
			(end 2.450084 -2.999994)
			(stroke
				(width 0)
				(type default)
			)
			(fill no)
			(layer "F.CrtYd")
		)
		(fp_poly
			(pts
				(xy -2.8194 3.6322) (xy -2.8194 -3.6322) (xy 2.8194 -3.6322) (xy 2.8194 1.18364) (xy 2.450084 1.18364)
				(xy 2.450084 -2.999994) (xy -2.450084 -2.999994) (xy -2.450084 2.999994) (xy 2.450084 2.999994)
				(xy 2.450084 1.18618) (xy 2.8194 1.18618) (xy 2.8194 3.6322)
			)
			(stroke
				(width 0)
				(type default)
			)
			(fill no)
			(layer "F.CrtYd")
		)
		(fp_rect
			(start -2.8194 3.6322)
			(end 2.8194 -3.6322)
			(stroke
				(width 0)
				(type default)
			)
			(fill no)
			(layer "F.Fab")
		)
		(pad "1" smd rect
			(at -1.905 2.54 180)
			(size 0.635 1.651)
			(layers "F.Cu" "F.Mask" "F.Paste")
			(net "EEPROM_A0")
		)
		(pad "2" smd rect
			(at -0.635 2.54 180)
			(size 0.635 1.651)
			(layers "F.Cu" "F.Mask" "F.Paste")
			(net "EEPROM_A1")
		)
		(pad "3" smd rect
			(at 0.635 2.54 180)
			(size 0.635 1.651)
			(layers "F.Cu" "F.Mask" "F.Paste")
			(net "EEPROM_A2")
		)
		(pad "4" smd rect
			(at 1.905 2.54 180)
			(size 0.635 1.651)
			(layers "F.Cu" "F.Mask" "F.Paste")
			(net "GND")
		)
		(pad "5" smd rect
			(at 1.905 -2.54 180)
			(size 0.635 1.651)
			(layers "F.Cu" "F.Mask" "F.Paste")
			(net "EEPROM_SDA")
		)
		(pad "6" smd rect
			(at 0.635 -2.54 180)
			(size 0.635 1.651)
			(layers "F.Cu" "F.Mask" "F.Paste")
			(net "EEPROM_SCL")
		)
		(pad "7" smd rect
			(at -0.635 -2.54 180)
			(size 0.635 1.651)
			(layers "F.Cu" "F.Mask" "F.Paste")
			(net "EEPROM_WP")
		)
		(pad "8" smd rect
			(at -1.905 -2.54 180)
			(size 0.635 1.651)
			(layers "F.Cu" "F.Mask" "F.Paste")
			(net "P3V3_STBY_B")
		)
	)
	(footprint ""
		(layer "F.Cu")
		(at 127.113284 -14.660626 90)
		(property "Reference" "C380"
			(at 0 0 90)
			(layer "F.SilkS")
			(hide yes)
			(effects
				(font
					(size 1.27 1.27)
				)
			)
		)
		(property "Value" "SCD01U16V1KX-GP"
			(at -2.8321 -1.7399 90)
			(unlocked yes)
			(layer "F.Fab")
			(hide yes)
			(effects
				(font
					(size 1.016 1.016)
					(thickness 0.1524)
				)
			)
		)
		(property "Device Type" "C0201H13"
			(at -2.8321 -3.2639 90)
			(unlocked yes)
			(layer "F.Fab")
			(hide yes)
			(effects
				(font
					(size 1.016 1.016)
					(thickness 0.1524)
				)
			)
		)
		(duplicate_pad_numbers_are_jumpers no)
		(fp_rect
			(start -0.2794 0.6477)
			(end 0.2794 -0.6477)
			(stroke
				(width 0)
				(type default)
			)
			(fill no)
			(layer "F.CrtYd")
		)
		(fp_rect
			(start -0.2794 0.6477)
			(end 0.2794 -0.6477)
			(stroke
				(width 0)
				(type default)
			)
			(fill no)
			(layer "F.Fab")
		)
		(pad "1" smd custom
			(at 0 -0.2794 90)
			(size 0.0762 0.0762)
			(layers "F.Cu" "F.Mask" "F.Paste")
			(net "SAS_HDD_RX_P27")
			(options
				(clearance outline)
				(anchor circle)
			)
			(primitives
				(gr_poly
					(pts
						(arc
							(start 0.1524 -0.127)
							(mid 0.137521 -0.162921)
							(end 0.1016 -0.1778)
						)
						(arc
							(start -0.1016 -0.1778)
							(mid -0.137521 -0.162921)
							(end -0.1524 -0.127)
						)
						(arc
							(start -0.1524 0.127)
							(mid -0.137521 0.162921)
							(end -0.1016 0.1778)
						)
						(arc
							(start 0.1016 0.1778)
							(mid 0.137521 0.162921)
							(end 0.1524 0.127)
						)
					)
					(width 0)
					(fill yes)
				)
			)
		)
		(pad "2" smd custom
			(at 0 0.2794 90)
			(size 0.0762 0.0762)
			(layers "F.Cu" "F.Mask" "F.Paste")
			(net "PHY_SCC_B_TO_DRV_B_27_DP")
			(options
				(clearance outline)
				(anchor circle)
			)
			(primitives
				(gr_poly
					(pts
						(arc
							(start 0.1524 -0.127)
							(mid 0.137521 -0.162921)
							(end 0.1016 -0.1778)
						)
						(arc
							(start -0.1016 -0.1778)
							(mid -0.137521 -0.162921)
							(end -0.1524 -0.127)
						)
						(arc
							(start -0.1524 0.127)
							(mid -0.137521 0.162921)
							(end -0.1016 0.1778)
						)
						(arc
							(start 0.1016 0.1778)
							(mid 0.137521 0.162921)
							(end 0.1524 0.127)
						)
					)
					(width 0)
					(fill yes)
				)
			)
		)
	)
	(footprint ""
		(layer "F.Cu")
		(at 176.276 -19.939 -90)
		(property "Reference" "R744"
			(at 0 0 270)
			(layer "F.SilkS")
			(hide yes)
			(effects
				(font
					(size 1.27 1.27)
				)
			)
		)
		(property "Value" "4K7R2J-2-GP"
			(at 0.064008 -3.993896 270)
			(unlocked yes)
			(layer "F.Fab")
			(hide yes)
			(effects
				(font
					(size 1.016 1.016)
					(thickness 0.1524)
				)
			)
		)
		(property "Device Type" "R402H16"
			(at 0.064008 -5.517896 270)
			(unlocked yes)
			(layer "F.Fab")
			(hide yes)
			(effects
				(font
					(size 1.016 1.016)
					(thickness 0.1524)
				)
			)
		)
		(duplicate_pad_numbers_are_jumpers no)
		(fp_line
			(start -0.508 -0.9398)
			(end -0.508 0.9398)
			(stroke
				(width 0.1524)
				(type default)
			)
			(layer "F.SilkS")
		)
		(fp_line
			(start 0.508 -0.9398)
			(end -0.508 -0.9398)
			(stroke
				(width 0.1524)
				(type default)
			)
			(layer "F.SilkS")
		)
		(fp_rect
			(start -0.508 0.9398)
			(end 0.508 -0.9398)
			(stroke
				(width 0)
				(type default)
			)
			(fill no)
			(layer "F.CrtYd")
		)
		(fp_rect
			(start -0.508 0.9398)
			(end 0.508 -0.9398)
			(stroke
				(width 0)
				(type default)
			)
			(fill no)
			(layer "F.Fab")
		)
		(pad "1" smd custom
			(at 0 -0.4445 270)
			(size 0.1397 0.1397)
			(layers "F.Cu" "F.Mask" "F.Paste")
			(net "P12V_B")
			(options
				(clearance outline)
				(anchor circle)
			)
			(primitives
				(gr_poly
					(pts
						(arc
							(start -0.1778 -0.2794)
							(mid -0.249642 -0.249642)
							(end -0.2794 -0.1778)
						)
						(arc
							(start -0.2794 0.1778)
							(mid -0.249642 0.249642)
							(end -0.1778 0.2794)
						)
						(arc
							(start 0.1778 0.2794)
							(mid 0.249642 0.249642)
							(end 0.2794 0.1778)
						)
						(arc
							(start 0.2794 -0.1778)
							(mid 0.249642 -0.249642)
							(end 0.1778 -0.2794)
						)
					)
					(width 0)
					(fill yes)
				)
			)
		)
		(pad "2" smd custom
			(at 0 0.4445 270)
			(size 0.1397 0.1397)
			(layers "F.Cu" "F.Mask" "F.Paste")
			(net "SW_HDD_P29")
			(options
				(clearance outline)
				(anchor circle)
			)
			(primitives
				(gr_poly
					(pts
						(arc
							(start -0.1778 -0.2794)
							(mid -0.249642 -0.249642)
							(end -0.2794 -0.1778)
						)
						(arc
							(start -0.2794 0.1778)
							(mid -0.249642 0.249642)
							(end -0.1778 0.2794)
						)
						(arc
							(start 0.1778 0.2794)
							(mid 0.249642 0.249642)
							(end 0.2794 0.1778)
						)
						(arc
							(start 0.2794 -0.1778)
							(mid 0.249642 -0.249642)
							(end 0.1778 -0.2794)
						)
					)
					(width 0)
					(fill yes)
				)
			)
		)
	)
	(footprint ""
		(layer "F.Cu")
		(at 141.097 -260.858)
		(property "Reference" "Q16"
			(at 0 0 0)
			(layer "F.SilkS")
			(hide yes)
			(effects
				(font
					(size 1.27 1.27)
				)
			)
		)
		(property "Value" "AO4407AL-GP"
			(at -3.707384 -1.5367 0)
			(unlocked yes)
			(layer "F.Fab")
			(hide yes)
			(effects
				(font
					(size 1.016 1.016)
					(thickness 0.1524)
				)
			)
		)
		(property "Device Type" "SOIC8H69"
			(at -3.707384 -3.0607 0)
			(unlocked yes)
			(layer "F.Fab")
			(hide yes)
			(effects
				(font
					(size 1.016 1.016)
					(thickness 0.1524)
				)
			)
		)
		(duplicate_pad_numbers_are_jumpers no)
		(fp_line
			(start -2.7432 -1.4224)
			(end -2.7432 1.4224)
			(stroke
				(width 0.1524)
				(type default)
			)
			(layer "F.SilkS")
		)
		(fp_line
			(start -2.7432 1.4224)
			(end -2.6416 1.4224)
			(stroke
				(width 0.1524)
				(type default)
			)
			(layer "F.SilkS")
		)
		(fp_line
			(start -2.7432 1.4224)
			(end 2.1336 1.4224)
			(stroke
				(width 0.1524)
				(type default)
			)
			(layer "F.SilkS")
		)
		(fp_line
			(start -2.7178 -0.508)
			(end -2.1844 -0.0508)
			(stroke
				(width 0.1524)
				(type default)
			)
			(layer "F.SilkS")
		)
		(fp_line
			(start -2.6289 3.4417)
			(end -2.6289 1.4732)
			(stroke
				(width 0.381)
				(type default)
			)
			(layer "F.SilkS")
		)
		(fp_line
			(start -2.1844 -0.0508)
			(end -2.7178 0.508)
			(stroke
				(width 0.1524)
				(type default)
			)
			(layer "F.SilkS")
		)
		(fp_line
			(start 2.1336 -1.4224)
			(end -2.7432 -1.4224)
			(stroke
				(width 0.1524)
				(type default)
			)
			(layer "F.SilkS")
		)
		(fp_line
			(start 2.1336 1.4224)
			(end 2.1336 -1.4224)
			(stroke
				(width 0.1524)
				(type default)
			)
			(layer "F.SilkS")
		)
		(fp_poly
			(pts
				(xy -2.2098 -1.4224) (xy -2.2098 1.4224) (xy 2.2098 1.4224) (xy 2.2098 -1.4224)
			)
			(stroke
				(width 0)
				(type default)
			)
			(fill yes)
			(layer "F.SilkS")
		)
		(fp_rect
			(start -2.450084 2.999994)
			(end 2.450084 -2.999994)
			(stroke
				(width 0)
				(type default)
			)
			(fill no)
			(layer "F.CrtYd")
		)
		(fp_poly
			(pts
				(xy -2.8194 3.6322) (xy -2.8194 -3.6322) (xy 2.8194 -3.6322) (xy 2.8194 1.18364) (xy 2.450084 1.18364)
				(xy 2.450084 -2.999994) (xy -2.450084 -2.999994) (xy -2.450084 2.999994) (xy 2.450084 2.999994)
				(xy 2.450084 1.18618) (xy 2.8194 1.18618) (xy 2.8194 3.6322)
			)
			(stroke
				(width 0)
				(type default)
			)
			(fill no)
			(layer "F.CrtYd")
		)
		(fp_rect
			(start -2.8194 3.6322)
			(end 2.8194 -3.6322)
			(stroke
				(width 0)
				(type default)
			)
			(fill no)
			(layer "F.Fab")
		)
		(pad "1" smd rect
			(at -1.905 2.54)
			(size 0.635 1.651)
			(layers "F.Cu" "F.Mask" "F.Paste")
			(net "P12V_B")
		)
		(pad "2" smd rect
			(at -0.635 2.54)
			(size 0.635 1.651)
			(layers "F.Cu" "F.Mask" "F.Paste")
			(net "P12V_B")
		)
		(pad "3" smd rect
			(at 0.635 2.54)
			(size 0.635 1.651)
			(layers "F.Cu" "F.Mask" "F.Paste")
			(net "P12V_B")
		)
		(pad "4" smd rect
			(at 1.905 2.54)
			(size 0.635 1.651)
			(layers "F.Cu" "F.Mask" "F.Paste")
			(net "SW_HDD_N4")
		)
		(pad "5" smd rect
			(at 1.905 -2.54)
			(size 0.635 1.651)
			(layers "F.Cu" "F.Mask" "F.Paste")
			(net "P12V_HDD4")
		)
		(pad "6" smd rect
			(at 0.635 -2.54)
			(size 0.635 1.651)
			(layers "F.Cu" "F.Mask" "F.Paste")
			(net "P12V_HDD4")
		)
		(pad "7" smd rect
			(at -0.635 -2.54)
			(size 0.635 1.651)
			(layers "F.Cu" "F.Mask" "F.Paste")
			(net "P12V_HDD4")
		)
		(pad "8" smd rect
			(at -1.905 -2.54)
			(size 0.635 1.651)
			(layers "F.Cu" "F.Mask" "F.Paste")
			(net "P12V_HDD4")
		)
	)
)
